(kicad_pcb
	(version 20241229)
	(generator "pcbnew")
	(generator_version "9.0")
	(general
		(thickness 1.62)
		(legacy_teardrops no)
	)
	(paper "A3")
	(title_block
		(title "COM Express 7 Baseboard")
		(date "2025-02-04")
		(rev "1.1.2")
		(company "Antmicro Ltd")
		(comment 1 "www.antmicro.com")
		(comment 9 "footprint 244 of 802 (U43), pads 40-79 of 144")
	)
	(layers
		(0 "F.Cu" signal)
		(4 "In1.Cu" signal)
		(6 "In2.Cu" signal)
		(8 "In3.Cu" signal)
		(10 "In4.Cu" signal)
		(12 "In5.Cu" signal)
		(14 "In6.Cu" signal)
		(2 "B.Cu" signal)
		(9 "F.Adhes" user "F.Adhesive")
		(11 "B.Adhes" user "B.Adhesive")
		(13 "F.Paste" user)
		(15 "B.Paste" user)
		(5 "F.SilkS" user "F.Silkscreen")
		(7 "B.SilkS" user "B.Silkscreen")
		(1 "F.Mask" user)
		(3 "B.Mask" user)
		(17 "Dwgs.User" user "User.Drawings")
		(19 "Cmts.User" user "User.Comments")
		(21 "Eco1.User" user "User.Eco1")
		(23 "Eco2.User" user "User.Eco2")
		(25 "Edge.Cuts" user)
		(27 "Margin" user)
		(31 "F.CrtYd" user "F.Courtyard")
		(29 "B.CrtYd" user "B.Courtyard")
		(35 "F.Fab" user)
		(33 "B.Fab" user)
	)
	(footprint "antmicro-footprints:BGA-144_12x12_13.05x13.05mm_P1.0mm"
		(layer "F.Cu")
		(at 150.95 137.36 -90)
		(property "Reference" "U43"
			(at 7.9 4.65 180)
			(layer "F.SilkS")
			(effects
				(font
					(size 0.7 0.7)
					(thickness 0.15)
				)
				(justify right bottom)
			)
		)
		(property "Value" "TLK10232CTR"
			(at 0 7.525 90)
			(layer "F.Fab")
			(effects
				(font
					(size 0.7 0.7)
					(thickness 0.15)
				)
				(justify right bottom)
			)
		)
		(property "Datasheet" "https://www.ti.com/lit/ds/symlink/tlk10232.pdf?ts=1712150848075&ref_url=https%253A%252F%252Fwww.mouser.pl%252F"
			(at 0 0 270)
			(layer "F.Fab")
			(hide yes)
			(effects
				(font
					(size 1.27 1.27)
					(thickness 0.15)
				)
			)
		)
		(property "Author" "Antmicro"
			(at 13.59 288.31 0)
			(layer "F.Fab")
			(hide yes)
			(effects
				(font
					(size 1 1)
					(thickness 0.15)
				)
			)
		)
		(property "License" "Apache-2.0"
			(at 13.59 288.31 0)
			(layer "F.Fab")
			(hide yes)
			(effects
				(font
					(size 1 1)
					(thickness 0.15)
				)
			)
		)
		(property "MPN" "TLK10232CTR"
			(at 13.59 288.31 0)
			(layer "F.Fab")
			(hide yes)
			(effects
				(font
					(size 1 1)
					(thickness 0.15)
				)
			)
		)
		(property "Manufacturer" "Texas Instruments"
			(at 13.59 288.31 0)
			(layer "F.Fab")
			(hide yes)
			(effects
				(font
					(size 1 1)
					(thickness 0.15)
				)
			)
		)
		(sheetname "KR to SFI #1")
		(sheetfile "kr_sfi.kicad_sch")
		(attr smd)
		(pad "D4" smd circle
			(at -2.5 -2.5 270)
			(size 0.5 0.5)
			(layers "F.Cu" "F.Mask" "F.Paste")
			(net 729 "Net-(U43C-AMUXB)")
			(pinfunction "AMUXB")
			(pintype "passive")
			(solder_mask_margin 0.05)
			(teardrops
				(best_length_ratio 0.4)
				(max_length 1)
				(best_width_ratio 0.9)
				(max_width 2)
				(curved_edges yes)
				(filter_ratio 0.9)
				(enabled yes)
				(allow_two_segments yes)
				(prefer_zone_connections yes)
			)
		)
		(pad "D5" smd circle
			(at -1.5 -2.5 270)
			(size 0.5 0.5)
			(layers "F.Cu" "F.Mask" "F.Paste")
			(net 1 "GND")
			(pinfunction "GND")
			(pintype "passive")
			(solder_mask_margin 0.05)
			(teardrops
				(best_length_ratio 0.4)
				(max_length 1)
				(best_width_ratio 0.9)
				(max_width 2)
				(curved_edges yes)
				(filter_ratio 0.9)
				(enabled yes)
				(allow_two_segments yes)
				(prefer_zone_connections yes)
			)
		)
		(pad "D6" smd circle
			(at -0.5 -2.5 270)
			(size 0.5 0.5)
			(layers "F.Cu" "F.Mask" "F.Paste")
			(net 723 "/2xSFP+/KR to SFI #1/TDO")
			(pinfunction "TDO")
			(pintype "output")
			(solder_mask_margin 0.05)
			(teardrops
				(best_length_ratio 0.4)
				(max_length 1)
				(best_width_ratio 0.9)
				(max_width 2)
				(curved_edges yes)
				(filter_ratio 0.9)
				(enabled yes)
				(allow_two_segments yes)
				(prefer_zone_connections yes)
			)
		)
		(pad "D7" smd circle
			(at 0.5 -2.5 270)
			(size 0.5 0.5)
			(layers "F.Cu" "F.Mask" "F.Paste")
			(net 74 "+1V0")
			(pinfunction "VPP")
			(pintype "power_in")
			(solder_mask_margin 0.05)
			(teardrops
				(best_length_ratio 0.4)
				(max_length 1)
				(best_width_ratio 0.9)
				(max_width 2)
				(curved_edges yes)
				(filter_ratio 0.9)
				(enabled yes)
				(allow_two_segments yes)
				(prefer_zone_connections yes)
			)
		)
		(pad "D8" smd circle
			(at 1.5 -2.5 270)
			(size 0.5 0.5)
			(layers "F.Cu" "F.Mask" "F.Paste")
			(net 725 "/2xSFP+/KR to SFI #1/TCK")
			(pinfunction "TCK")
			(pintype "input")
			(solder_mask_margin 0.05)
			(teardrops
				(best_length_ratio 0.4)
				(max_length 1)
				(best_width_ratio 0.9)
				(max_width 2)
				(curved_edges yes)
				(filter_ratio 0.9)
				(enabled yes)
				(allow_two_segments yes)
				(prefer_zone_connections yes)
			)
		)
		(pad "D9" smd circle
			(at 2.5 -2.5 270)
			(size 0.5 0.5)
			(layers "F.Cu" "F.Mask" "F.Paste")
			(net 736 "Net-(U43A-LS_OK_{OUT_A})")
			(pinfunction "LS_OK_{OUT_A}")
			(pintype "output")
			(solder_mask_margin 0.05)
			(teardrops
				(best_length_ratio 0.4)
				(max_length 1)
				(best_width_ratio 0.9)
				(max_width 2)
				(curved_edges yes)
				(filter_ratio 0.9)
				(enabled yes)
				(allow_two_segments yes)
				(prefer_zone_connections yes)
			)
		)
		(pad "D10" smd circle
			(at 3.5 -2.5 270)
			(size 0.5 0.5)
			(layers "F.Cu" "F.Mask" "F.Paste")
			(net 1 "GND")
			(pinfunction "GND")
			(pintype "passive")
			(solder_mask_margin 0.05)
			(teardrops
				(best_length_ratio 0.4)
				(max_length 1)
				(best_width_ratio 0.9)
				(max_width 2)
				(curved_edges yes)
				(filter_ratio 0.9)
				(enabled yes)
				(allow_two_segments yes)
				(prefer_zone_connections yes)
			)
		)
		(pad "D11" smd circle
			(at 4.5 -2.5 270)
			(size 0.5 0.5)
			(layers "F.Cu" "F.Mask" "F.Paste")
			(net 1 "GND")
			(pinfunction "GND")
			(pintype "passive")
			(solder_mask_margin 0.05)
			(teardrops
				(best_length_ratio 0.4)
				(max_length 1)
				(best_width_ratio 0.9)
				(max_width 2)
				(curved_edges yes)
				(filter_ratio 0.9)
				(enabled yes)
				(allow_two_segments yes)
				(prefer_zone_connections yes)
			)
		)
		(pad "D12" smd circle
			(at 5.5 -2.5 270)
			(size 0.5 0.5)
			(layers "F.Cu" "F.Mask" "F.Paste")
			(net 664 "/2xSFP+/KR to SFI #1/KR_R.RX+")
			(pinfunction "HSTXA+")
			(pintype "output")
			(solder_mask_margin 0.05)
			(teardrops
				(best_length_ratio 0.4)
				(max_length 1)
				(best_width_ratio 0.9)
				(max_width 2)
				(curved_edges yes)
				(filter_ratio 0.9)
				(enabled yes)
				(allow_two_segments yes)
				(prefer_zone_connections yes)
			)
		)
		(pad "E1" smd circle
			(at -5.5 -1.5 270)
			(size 0.5 0.5)
			(layers "F.Cu" "F.Mask" "F.Paste")
			(net 813 "unconnected-(U43A-INA3--PadE1)")
			(pinfunction "INA3-")
			(pintype "input+no_connect")
			(solder_mask_margin 0.05)
			(teardrops
				(best_length_ratio 0.4)
				(max_length 1)
				(best_width_ratio 0.9)
				(max_width 2)
				(curved_edges yes)
				(filter_ratio 0.9)
				(enabled yes)
				(allow_two_segments yes)
				(prefer_zone_connections yes)
			)
		)
		(pad "E2" smd circle
			(at -4.5 -1.5 270)
			(size 0.5 0.5)
			(layers "F.Cu" "F.Mask" "F.Paste")
			(net 1 "GND")
			(pinfunction "GND")
			(pintype "passive")
			(solder_mask_margin 0.05)
			(teardrops
				(best_length_ratio 0.4)
				(max_length 1)
				(best_width_ratio 0.9)
				(max_width 2)
				(curved_edges yes)
				(filter_ratio 0.9)
				(enabled yes)
				(allow_two_segments yes)
				(prefer_zone_connections yes)
			)
		)
		(pad "E3" smd circle
			(at -3.5 -1.5 270)
			(size 0.5 0.5)
			(layers "F.Cu" "F.Mask" "F.Paste")
			(net 814 "unconnected-(U43A-OUTA3--PadE3)")
			(pinfunction "OUTA3-")
			(pintype "output+no_connect")
			(solder_mask_margin 0.05)
			(teardrops
				(best_length_ratio 0.4)
				(max_length 1)
				(best_width_ratio 0.9)
				(max_width 2)
				(curved_edges yes)
				(filter_ratio 0.9)
				(enabled yes)
				(allow_two_segments yes)
				(prefer_zone_connections yes)
			)
		)
		(pad "E4" smd circle
			(at -2.5 -1.5 270)
			(size 0.5 0.5)
			(layers "F.Cu" "F.Mask" "F.Paste")
			(net 1 "GND")
			(pinfunction "GND")
			(pintype "passive")
			(solder_mask_margin 0.05)
			(teardrops
				(best_length_ratio 0.4)
				(max_length 1)
				(best_width_ratio 0.9)
				(max_width 2)
				(curved_edges yes)
				(filter_ratio 0.9)
				(enabled yes)
				(allow_two_segments yes)
				(prefer_zone_connections yes)
			)
		)
		(pad "E5" smd circle
			(at -1.5 -1.5 270)
			(size 0.5 0.5)
			(layers "F.Cu" "F.Mask" "F.Paste")
			(net 726 "/2xSFP+/KR to SFI #1/~{TRST}")
			(pinfunction "~{TRST}")
			(pintype "input")
			(solder_mask_margin 0.05)
			(teardrops
				(best_length_ratio 0.4)
				(max_length 1)
				(best_width_ratio 0.9)
				(max_width 2)
				(curved_edges yes)
				(filter_ratio 0.9)
				(enabled yes)
				(allow_two_segments yes)
				(prefer_zone_connections yes)
			)
		)
		(pad "E6" smd circle
			(at -0.5 -1.5 270)
			(size 0.5 0.5)
			(layers "F.Cu" "F.Mask" "F.Paste")
			(net 74 "+1V0")
			(pinfunction "VDDD")
			(pintype "power_in")
			(solder_mask_margin 0.05)
			(teardrops
				(best_length_ratio 0.4)
				(max_length 1)
				(best_width_ratio 0.9)
				(max_width 2)
				(curved_edges yes)
				(filter_ratio 0.9)
				(enabled yes)
				(allow_two_segments yes)
				(prefer_zone_connections yes)
			)
		)
		(pad "E7" smd circle
			(at 0.5 -1.5 270)
			(size 0.5 0.5)
			(layers "F.Cu" "F.Mask" "F.Paste")
			(net 74 "+1V0")
			(pinfunction "DVDD")
			(pintype "power_in")
			(solder_mask_margin 0.05)
			(teardrops
				(best_length_ratio 0.4)
				(max_length 1)
				(best_width_ratio 0.9)
				(max_width 2)
				(curved_edges yes)
				(filter_ratio 0.9)
				(enabled yes)
				(allow_two_segments yes)
				(prefer_zone_connections yes)
			)
		)
		(pad "E8" smd circle
			(at 1.5 -1.5 270)
			(size 0.5 0.5)
			(layers "F.Cu" "F.Mask" "F.Paste")
			(net 74 "+1V0")
			(pinfunction "VDDD")
			(pintype "passive")
			(solder_mask_margin 0.05)
			(teardrops
				(best_length_ratio 0.4)
				(max_length 1)
				(best_width_ratio 0.9)
				(max_width 2)
				(curved_edges yes)
				(filter_ratio 0.9)
				(enabled yes)
				(allow_two_segments yes)
				(prefer_zone_connections yes)
			)
		)
		(pad "E9" smd circle
			(at 2.5 -1.5 270)
			(size 0.5 0.5)
			(layers "F.Cu" "F.Mask" "F.Paste")
			(net 734 "Net-(U43A-LOSA)")
			(pinfunction "LOSA")
			(pintype "output")
			(solder_mask_margin 0.05)
			(teardrops
				(best_length_ratio 0.4)
				(max_length 1)
				(best_width_ratio 0.9)
				(max_width 2)
				(curved_edges yes)
				(filter_ratio 0.9)
				(enabled yes)
				(allow_two_segments yes)
				(prefer_zone_connections yes)
			)
		)
		(pad "E10" smd circle
			(at 3.5 -1.5 270)
			(size 0.5 0.5)
			(layers "F.Cu" "F.Mask" "F.Paste")
			(net 655 "Net-(U43C-PRTAD0)")
			(pinfunction "PRTAD0")
			(pintype "input")
			(solder_mask_margin 0.05)
			(teardrops
				(best_length_ratio 0.4)
				(max_length 1)
				(best_width_ratio 0.9)
				(max_width 2)
				(curved_edges yes)
				(filter_ratio 0.9)
				(enabled yes)
				(allow_two_segments yes)
				(prefer_zone_connections yes)
			)
		)
		(pad "E11" smd circle
			(at 4.5 -1.5 270)
			(size 0.5 0.5)
			(layers "F.Cu" "F.Mask" "F.Paste")
			(net 78 "+1V8")
			(pinfunction "VDDRA_{LS/HS}")
			(pintype "passive")
			(solder_mask_margin 0.05)
			(teardrops
				(best_length_ratio 0.4)
				(max_length 1)
				(best_width_ratio 0.9)
				(max_width 2)
				(curved_edges yes)
				(filter_ratio 0.9)
				(enabled yes)
				(allow_two_segments yes)
				(prefer_zone_connections yes)
			)
		)
		(pad "E12" smd circle
			(at 5.5 -1.5 270)
			(size 0.5 0.5)
			(layers "F.Cu" "F.Mask" "F.Paste")
			(net 665 "/2xSFP+/KR to SFI #1/KR_R.RX-")
			(pinfunction "HSTXA-")
			(pintype "output")
			(solder_mask_margin 0.05)
			(teardrops
				(best_length_ratio 0.4)
				(max_length 1)
				(best_width_ratio 0.9)
				(max_width 2)
				(curved_edges yes)
				(filter_ratio 0.9)
				(enabled yes)
				(allow_two_segments yes)
				(prefer_zone_connections yes)
			)
		)
		(pad "F1" smd circle
			(at -5.5 -0.5 270)
			(size 0.5 0.5)
			(layers "F.Cu" "F.Mask" "F.Paste")
			(net 1 "GND")
			(pinfunction "GND")
			(pintype "passive")
			(solder_mask_margin 0.05)
			(teardrops
				(best_length_ratio 0.4)
				(max_length 1)
				(best_width_ratio 0.9)
				(max_width 2)
				(curved_edges yes)
				(filter_ratio 0.9)
				(enabled yes)
				(allow_two_segments yes)
				(prefer_zone_connections yes)
			)
		)
		(pad "F2" smd circle
			(at -4.5 -0.5 270)
			(size 0.5 0.5)
			(layers "F.Cu" "F.Mask" "F.Paste")
			(net 74 "+1V0")
			(pinfunction "VDDA_{LS/HS}")
			(pintype "passive")
			(solder_mask_margin 0.05)
			(teardrops
				(best_length_ratio 0.4)
				(max_length 1)
				(best_width_ratio 0.9)
				(max_width 2)
				(curved_edges yes)
				(filter_ratio 0.9)
				(enabled yes)
				(allow_two_segments yes)
				(prefer_zone_connections yes)
			)
		)
		(pad "F3" smd circle
			(at -3.5 -0.5 270)
			(size 0.5 0.5)
			(layers "F.Cu" "F.Mask" "F.Paste")
			(net 815 "unconnected-(U43A-OUTA3+-PadF3)")
			(pinfunction "OUTA3+")
			(pintype "output+no_connect")
			(solder_mask_margin 0.05)
			(teardrops
				(best_length_ratio 0.4)
				(max_length 1)
				(best_width_ratio 0.9)
				(max_width 2)
				(curved_edges yes)
				(filter_ratio 0.9)
				(enabled yes)
				(allow_two_segments yes)
				(prefer_zone_connections yes)
			)
		)
		(pad "F4" smd circle
			(at -2.5 -0.5 270)
			(size 0.5 0.5)
			(layers "F.Cu" "F.Mask" "F.Paste")
			(net 74 "+1V0")
			(pinfunction "VDDT_{LS/HS}")
			(pintype "power_in")
			(solder_mask_margin 0.05)
			(teardrops
				(best_length_ratio 0.4)
				(max_length 1)
				(best_width_ratio 0.9)
				(max_width 2)
				(curved_edges yes)
				(filter_ratio 0.9)
				(enabled yes)
				(allow_two_segments yes)
				(prefer_zone_connections yes)
			)
		)
		(pad "F5" smd circle
			(at -1.5 -0.5 270)
			(size 0.5 0.5)
			(layers "F.Cu" "F.Mask" "F.Paste")
			(net 1 "GND")
			(pinfunction "GND")
			(pintype "passive")
			(solder_mask_margin 0.05)
			(teardrops
				(best_length_ratio 0.4)
				(max_length 1)
				(best_width_ratio 0.9)
				(max_width 2)
				(curved_edges yes)
				(filter_ratio 0.9)
				(enabled yes)
				(allow_two_segments yes)
				(prefer_zone_connections yes)
			)
		)
		(pad "F6" smd circle
			(at -0.5 -0.5 270)
			(size 0.5 0.5)
			(layers "F.Cu" "F.Mask" "F.Paste")
			(net 74 "+1V0")
			(pinfunction "VDDD")
			(pintype "passive")
			(solder_mask_margin 0.05)
			(teardrops
				(best_length_ratio 0.4)
				(max_length 1)
				(best_width_ratio 0.9)
				(max_width 2)
				(curved_edges yes)
				(filter_ratio 0.9)
				(enabled yes)
				(allow_two_segments yes)
				(prefer_zone_connections yes)
			)
		)
		(pad "F7" smd circle
			(at 0.5 -0.5 270)
			(size 0.5 0.5)
			(layers "F.Cu" "F.Mask" "F.Paste")
			(net 74 "+1V0")
			(pinfunction "DVDD")
			(pintype "passive")
			(solder_mask_margin 0.05)
			(teardrops
				(best_length_ratio 0.4)
				(max_length 1)
				(best_width_ratio 0.9)
				(max_width 2)
				(curved_edges yes)
				(filter_ratio 0.9)
				(enabled yes)
				(allow_two_segments yes)
				(prefer_zone_connections yes)
			)
		)
		(pad "F8" smd circle
			(at 1.5 -0.5 270)
			(size 0.5 0.5)
			(layers "F.Cu" "F.Mask" "F.Paste")
			(net 1 "GND")
			(pinfunction "GND")
			(pintype "passive")
			(solder_mask_margin 0.05)
			(teardrops
				(best_length_ratio 0.4)
				(max_length 1)
				(best_width_ratio 0.9)
				(max_width 2)
				(curved_edges yes)
				(filter_ratio 0.9)
				(enabled yes)
				(allow_two_segments yes)
				(prefer_zone_connections yes)
			)
		)
		(pad "F9" smd circle
			(at 2.5 -0.5 270)
			(size 0.5 0.5)
			(layers "F.Cu" "F.Mask" "F.Paste")
			(net 74 "+1V0")
			(pinfunction "VDDT_{LS/HS}")
			(pintype "passive")
			(solder_mask_margin 0.05)
			(teardrops
				(best_length_ratio 0.4)
				(max_length 1)
				(best_width_ratio 0.9)
				(max_width 2)
				(curved_edges yes)
				(filter_ratio 0.9)
				(enabled yes)
				(allow_two_segments yes)
				(prefer_zone_connections yes)
			)
		)
		(pad "F10" smd circle
			(at 3.5 -0.5 270)
			(size 0.5 0.5)
			(layers "F.Cu" "F.Mask" "F.Paste")
			(net 1 "GND")
			(pinfunction "GND")
			(pintype "passive")
			(solder_mask_margin 0.05)
			(teardrops
				(best_length_ratio 0.4)
				(max_length 1)
				(best_width_ratio 0.9)
				(max_width 2)
				(curved_edges yes)
				(filter_ratio 0.9)
				(enabled yes)
				(allow_two_segments yes)
				(prefer_zone_connections yes)
			)
		)
		(pad "F11" smd circle
			(at 4.5 -0.5 270)
			(size 0.5 0.5)
			(layers "F.Cu" "F.Mask" "F.Paste")
			(net 74 "+1V0")
			(pinfunction "VDDA_{LS/HS}")
			(pintype "passive")
			(solder_mask_margin 0.05)
			(teardrops
				(best_length_ratio 0.4)
				(max_length 1)
				(best_width_ratio 0.9)
				(max_width 2)
				(curved_edges yes)
				(filter_ratio 0.9)
				(enabled yes)
				(allow_two_segments yes)
				(prefer_zone_connections yes)
			)
		)
		(pad "F12" smd circle
			(at 5.5 -0.5 270)
			(size 0.5 0.5)
			(layers "F.Cu" "F.Mask" "F.Paste")
			(net 1 "GND")
			(pinfunction "GND")
			(pintype "passive")
			(solder_mask_margin 0.05)
			(teardrops
				(best_length_ratio 0.4)
				(max_length 1)
				(best_width_ratio 0.9)
				(max_width 2)
				(curved_edges yes)
				(filter_ratio 0.9)
				(enabled yes)
				(allow_two_segments yes)
				(prefer_zone_connections yes)
			)
		)
		(pad "G1" smd circle
			(at -5.5 0.5 270)
			(size 0.5 0.5)
			(layers "F.Cu" "F.Mask" "F.Paste")
			(net 1 "GND")
			(pinfunction "GND")
			(pintype "passive")
			(solder_mask_margin 0.05)
			(teardrops
				(best_length_ratio 0.4)
				(max_length 1)
				(best_width_ratio 0.9)
				(max_width 2)
				(curved_edges yes)
				(filter_ratio 0.9)
				(enabled yes)
				(allow_two_segments yes)
				(prefer_zone_connections yes)
			)
		)
		(pad "G2" smd circle
			(at -4.5 0.5 270)
			(size 0.5 0.5)
			(layers "F.Cu" "F.Mask" "F.Paste")
			(net 74 "+1V0")
			(pinfunction "VDDA_{LS/HS}")
			(pintype "passive")
			(solder_mask_margin 0.05)
			(teardrops
				(best_length_ratio 0.4)
				(max_length 1)
				(best_width_ratio 0.9)
				(max_width 2)
				(curved_edges yes)
				(filter_ratio 0.9)
				(enabled yes)
				(allow_two_segments yes)
				(prefer_zone_connections yes)
			)
		)
		(pad "G3" smd circle
			(at -3.5 0.5 270)
			(size 0.5 0.5)
			(layers "F.Cu" "F.Mask" "F.Paste")
			(net 1 "GND")
			(pinfunction "GND")
			(pintype "passive")
			(solder_mask_margin 0.05)
			(teardrops
				(best_length_ratio 0.4)
				(max_length 1)
				(best_width_ratio 0.9)
				(max_width 2)
				(curved_edges yes)
				(filter_ratio 0.9)
				(enabled yes)
				(allow_two_segments yes)
				(prefer_zone_connections yes)
			)
		)
		(pad "G4" smd circle
			(at -2.5 0.5 270)
			(size 0.5 0.5)
			(layers "F.Cu" "F.Mask" "F.Paste")
			(net 74 "+1V0")
			(pinfunction "VDDT_{LS/HS}")
			(pintype "passive")
			(solder_mask_margin 0.05)
			(teardrops
				(best_length_ratio 0.4)
				(max_length 1)
				(best_width_ratio 0.9)
				(max_width 2)
				(curved_edges yes)
				(filter_ratio 0.9)
				(enabled yes)
				(allow_two_segments yes)
				(prefer_zone_connections yes)
			)
		)
		(pad "G5" smd circle
			(at -1.5 0.5 270)
			(size 0.5 0.5)
			(layers "F.Cu" "F.Mask" "F.Paste")
			(net 1 "GND")
			(pinfunction "GND")
			(pintype "passive")
			(solder_mask_margin 0.05)
			(teardrops
				(best_length_ratio 0.4)
				(max_length 1)
				(best_width_ratio 0.9)
				(max_width 2)
				(curved_edges yes)
				(filter_ratio 0.9)
				(enabled yes)
				(allow_two_segments yes)
				(prefer_zone_connections yes)
			)
		)
		(pad "G6" smd circle
			(at -0.5 0.5 270)
			(size 0.5 0.5)
			(layers "F.Cu" "F.Mask" "F.Paste")
			(net 74 "+1V0")
			(pinfunction "DVDD")
			(pintype "passive")
			(solder_mask_margin 0.05)
			(teardrops
				(best_length_ratio 0.4)
				(max_length 1)
				(best_width_ratio 0.9)
				(max_width 2)
				(curved_edges yes)
				(filter_ratio 0.9)
				(enabled yes)
				(allow_two_segments yes)
				(prefer_zone_connections yes)
			)
		)
		(pad "G7" smd circle
			(at 0.5 0.5 270)
			(size 0.5 0.5)
			(layers "F.Cu" "F.Mask" "F.Paste")
			(net 1 "GND")
			(pinfunction "GND")
			(pintype "passive")
			(solder_mask_margin 0.05)
			(teardrops
				(best_length_ratio 0.4)
				(max_length 1)
				(best_width_ratio 0.9)
				(max_width 2)
				(curved_edges yes)
				(filter_ratio 0.9)
				(enabled yes)
				(allow_two_segments yes)
				(prefer_zone_connections yes)
			)
		)
	)
)
